(kicad_pcb
	(version 20260206)
	(generator "pcbnew")
	(generator_version "10.0")
	(general
		(thickness 1.6)
		(legacy_teardrops no)
	)
	(paper "A4")
	(title_block
		(title "Bryce Canyon_Front Panel_16369-1_OCP.brd")
		(comment 1 "Bryce Canyon / footprints 133-138 of 154")
	)
	(layers
		(0 "F.Cu" signal "TOP")
		(4 "In1.Cu" signal "L2GND")
		(6 "In2.Cu" signal "L3VCC")
		(2 "B.Cu" signal "BOTTOM")
		(9 "F.Adhes" user "F.Adhesive")
		(11 "B.Adhes" user "B.Adhesive")
		(13 "F.Paste" user "Package Geometry/Pastemask Top")
		(15 "B.Paste" user "Package Geometry/Pastemask Bottom")
		(5 "F.SilkS" user "Ref Des/Silkscreen Top")
		(7 "B.SilkS" user "Ref Des/Silkscreen Bottom")
		(1 "F.Mask" user "Board Geometry/Soldermask Top")
		(3 "B.Mask" user "Board Geometry/Soldermask Bottom")
		(17 "Dwgs.User" user "User.Drawings")
		(19 "Cmts.User" user "User.Comments")
		(21 "Eco1.User" user "User.Eco1")
		(23 "Eco2.User" user "User.Eco2")
		(25 "Edge.Cuts" user "Board Geometry/Outline")
		(27 "Margin" user)
		(31 "F.CrtYd" user "Package Geometry/Place Bound Top")
		(29 "B.CrtYd" user "Package Geometry/Place Bound Bottom")
		(35 "F.Fab" user "Ref Des/Assembly Top")
		(33 "B.Fab" user "Ref Des/Assembly Bottom")
	)
	(footprint ""
		(layer "F.Cu")
		(at 8.128 -72.136 -90)
		(property "Reference" "R45"
			(at 0 0 270)
			(layer "F.SilkS")
			(hide yes)
			(effects
				(font
					(size 1.27 1.27)
				)
			)
		)
		(property "Value" "1MR2F-GP"
			(at 0.064008 -4.679696 270)
			(unlocked yes)
			(layer "F.Fab")
			(hide yes)
			(effects
				(font
					(size 2.54 2.54)
					(thickness 0.381)
				)
			)
		)
		(property "Device Type" "R402H16"
			(at 0.064008 -6.203696 270)
			(unlocked yes)
			(layer "F.Fab")
			(hide yes)
			(effects
				(font
					(size 2.54 2.54)
					(thickness 0.381)
				)
			)
		)
		(duplicate_pad_numbers_are_jumpers no)
		(fp_line
			(start -0.508 -0.9398)
			(end -0.508 0.9398)
			(stroke
				(width 0.1524)
				(type default)
			)
			(layer "F.SilkS")
		)
		(fp_line
			(start 0.508 -0.9398)
			(end -0.508 -0.9398)
			(stroke
				(width 0.1524)
				(type default)
			)
			(layer "F.SilkS")
		)
		(fp_rect
			(start -0.508 0.9398)
			(end 0.508 -0.9398)
			(stroke
				(width 0)
				(type default)
			)
			(fill no)
			(layer "F.CrtYd")
		)
		(fp_rect
			(start -0.508 0.9398)
			(end 0.508 -0.9398)
			(stroke
				(width 0)
				(type default)
			)
			(fill no)
			(layer "F.Fab")
		)
		(pad "1" smd custom
			(at 0 -0.4445 270)
			(size 0.1397 0.1397)
			(layers "F.Cu" "F.Mask" "F.Paste")
			(net "USB_CONN_A_GND")
			(options
				(clearance outline)
				(anchor circle)
			)
			(primitives
				(gr_poly
					(pts
						(arc
							(start -0.1778 -0.2794)
							(mid -0.249642 -0.249642)
							(end -0.2794 -0.1778)
						)
						(arc
							(start -0.2794 0.1778)
							(mid -0.249642 0.249642)
							(end -0.1778 0.2794)
						)
						(arc
							(start 0.1778 0.2794)
							(mid 0.249642 0.249642)
							(end 0.2794 0.1778)
						)
						(arc
							(start 0.2794 -0.1778)
							(mid 0.249642 -0.249642)
							(end 0.1778 -0.2794)
						)
					)
					(width 0)
					(fill yes)
				)
			)
		)
		(pad "2" smd custom
			(at 0 0.4445 270)
			(size 0.1397 0.1397)
			(layers "F.Cu" "F.Mask" "F.Paste")
			(net "GND")
			(options
				(clearance outline)
				(anchor circle)
			)
			(primitives
				(gr_poly
					(pts
						(arc
							(start -0.1778 -0.2794)
							(mid -0.249642 -0.249642)
							(end -0.2794 -0.1778)
						)
						(arc
							(start -0.2794 0.1778)
							(mid -0.249642 0.249642)
							(end -0.1778 0.2794)
						)
						(arc
							(start 0.1778 0.2794)
							(mid 0.249642 0.249642)
							(end 0.2794 0.1778)
						)
						(arc
							(start 0.2794 -0.1778)
							(mid 0.249642 -0.249642)
							(end 0.1778 -0.2794)
						)
					)
					(width 0)
					(fill yes)
				)
			)
		)
	)
	(footprint ""
		(layer "F.Cu")
		(at 13.840968 -46.640496)
		(property "Reference" "R33"
			(at 0 0 0)
			(layer "F.SilkS")
			(hide yes)
			(effects
				(font
					(size 1.27 1.27)
				)
			)
		)
		(property "Value" "4K7R2F-GP"
			(at 0.064008 -4.679696 0)
			(unlocked yes)
			(layer "F.Fab")
			(hide yes)
			(effects
				(font
					(size 2.54 2.54)
					(thickness 0.381)
				)
			)
		)
		(property "Device Type" "R402H16"
			(at 0.064008 -6.203696 0)
			(unlocked yes)
			(layer "F.Fab")
			(hide yes)
			(effects
				(font
					(size 2.54 2.54)
					(thickness 0.381)
				)
			)
		)
		(duplicate_pad_numbers_are_jumpers no)
		(fp_line
			(start -0.508 -0.9398)
			(end -0.508 0.9398)
			(stroke
				(width 0.1524)
				(type default)
			)
			(layer "F.SilkS")
		)
		(fp_line
			(start 0.508 -0.9398)
			(end -0.508 -0.9398)
			(stroke
				(width 0.1524)
				(type default)
			)
			(layer "F.SilkS")
		)
		(fp_rect
			(start -0.508 0.9398)
			(end 0.508 -0.9398)
			(stroke
				(width 0)
				(type default)
			)
			(fill no)
			(layer "F.CrtYd")
		)
		(fp_rect
			(start -0.508 0.9398)
			(end 0.508 -0.9398)
			(stroke
				(width 0)
				(type default)
			)
			(fill no)
			(layer "F.Fab")
		)
		(pad "1" smd custom
			(at 0 -0.4445)
			(size 0.1397 0.1397)
			(layers "F.Cu" "F.Mask" "F.Paste")
			(net "P3V3_STBY_A")
			(options
				(clearance outline)
				(anchor circle)
			)
			(primitives
				(gr_poly
					(pts
						(arc
							(start -0.1778 -0.2794)
							(mid -0.249642 -0.249642)
							(end -0.2794 -0.1778)
						)
						(arc
							(start -0.2794 0.1778)
							(mid -0.249642 0.249642)
							(end -0.1778 0.2794)
						)
						(arc
							(start 0.1778 0.2794)
							(mid 0.249642 0.249642)
							(end 0.2794 0.1778)
						)
						(arc
							(start 0.2794 -0.1778)
							(mid 0.249642 -0.249642)
							(end 0.1778 -0.2794)
						)
					)
					(width 0)
					(fill yes)
				)
			)
		)
		(pad "2" smd custom
			(at 0 0.4445)
			(size 0.1397 0.1397)
			(layers "F.Cu" "F.Mask" "F.Paste")
			(net "TEMP_1_A1")
			(options
				(clearance outline)
				(anchor circle)
			)
			(primitives
				(gr_poly
					(pts
						(arc
							(start -0.1778 -0.2794)
							(mid -0.249642 -0.249642)
							(end -0.2794 -0.1778)
						)
						(arc
							(start -0.2794 0.1778)
							(mid -0.249642 0.249642)
							(end -0.1778 0.2794)
						)
						(arc
							(start 0.1778 0.2794)
							(mid 0.249642 0.249642)
							(end 0.2794 0.1778)
						)
						(arc
							(start 0.2794 -0.1778)
							(mid 0.249642 -0.249642)
							(end 0.1778 -0.2794)
						)
					)
					(width 0)
					(fill yes)
				)
			)
		)
	)
	(footprint ""
		(layer "F.Cu")
		(at 53.218588 -12.830048 180)
		(property "Reference" "R8"
			(at 0 0 180)
			(layer "F.SilkS")
			(hide yes)
			(effects
				(font
					(size 1.27 1.27)
				)
			)
		)
		(property "Value" "10KR2F-2-GP"
			(at 0.064008 -4.679696 180)
			(unlocked yes)
			(layer "F.Fab")
			(hide yes)
			(effects
				(font
					(size 2.54 2.54)
					(thickness 0.381)
				)
			)
		)
		(property "Device Type" "R402H16"
			(at 0.064008 -6.203696 180)
			(unlocked yes)
			(layer "F.Fab")
			(hide yes)
			(effects
				(font
					(size 2.54 2.54)
					(thickness 0.381)
				)
			)
		)
		(duplicate_pad_numbers_are_jumpers no)
		(fp_line
			(start 0.508 -0.9398)
			(end -0.508 -0.9398)
			(stroke
				(width 0.1524)
				(type default)
			)
			(layer "F.SilkS")
		)
		(fp_line
			(start -0.508 -0.9398)
			(end -0.508 0.9398)
			(stroke
				(width 0.1524)
				(type default)
			)
			(layer "F.SilkS")
		)
		(fp_rect
			(start -0.508 0.9398)
			(end 0.508 -0.9398)
			(stroke
				(width 0)
				(type default)
			)
			(fill no)
			(layer "F.CrtYd")
		)
		(fp_rect
			(start -0.508 0.9398)
			(end 0.508 -0.9398)
			(stroke
				(width 0)
				(type default)
			)
			(fill no)
			(layer "F.Fab")
		)
		(pad "1" smd custom
			(at 0 -0.4445 180)
			(size 0.1397 0.1397)
			(layers "F.Cu" "F.Mask" "F.Paste")
			(net "P3V3_STBY_B")
			(options
				(clearance outline)
				(anchor circle)
			)
			(primitives
				(gr_poly
					(pts
						(arc
							(start -0.1778 -0.2794)
							(mid -0.249642 -0.249642)
							(end -0.2794 -0.1778)
						)
						(arc
							(start -0.2794 0.1778)
							(mid -0.249642 0.249642)
							(end -0.1778 0.2794)
						)
						(arc
							(start 0.1778 0.2794)
							(mid 0.249642 0.249642)
							(end 0.2794 0.1778)
						)
						(arc
							(start 0.2794 -0.1778)
							(mid 0.249642 -0.249642)
							(end 0.1778 -0.2794)
						)
					)
					(width 0)
					(fill yes)
				)
			)
		)
		(pad "2" smd custom
			(at 0 0.4445 180)
			(size 0.1397 0.1397)
			(layers "F.Cu" "F.Mask" "F.Paste")
			(net "UART_SEL_B_MUX_R")
			(options
				(clearance outline)
				(anchor circle)
			)
			(primitives
				(gr_poly
					(pts
						(arc
							(start -0.1778 -0.2794)
							(mid -0.249642 -0.249642)
							(end -0.2794 -0.1778)
						)
						(arc
							(start -0.2794 0.1778)
							(mid -0.249642 0.249642)
							(end -0.1778 0.2794)
						)
						(arc
							(start 0.1778 0.2794)
							(mid 0.249642 0.249642)
							(end 0.2794 0.1778)
						)
						(arc
							(start 0.2794 -0.1778)
							(mid 0.249642 -0.249642)
							(end 0.1778 -0.2794)
						)
					)
					(width 0)
					(fill yes)
				)
			)
		)
	)
	(footprint ""
		(layer "F.Cu")
		(at 53.213 -19.177 90)
		(property "Reference" "U4"
			(at 0 0 90)
			(layer "F.SilkS")
			(hide yes)
			(effects
				(font
					(size 1.27 1.27)
				)
			)
		)
		(property "Value" "TCA9555PWR-GP"
			(at 0 -6.9342 90)
			(unlocked yes)
			(layer "F.Fab")
			(hide yes)
			(effects
				(font
					(size 1.016 1.016)
					(thickness 0.1524)
				)
			)
		)
		(property "Device Type" "TSOIC24H48"
			(at 0 -8.5852 90)
			(unlocked yes)
			(layer "F.Fab")
			(hide yes)
			(effects
				(font
					(size 1.016 1.016)
					(thickness 0.1524)
				)
			)
		)
		(duplicate_pad_numbers_are_jumpers no)
		(fp_line
			(start 3.81 -1.397)
			(end 3.81 1.397)
			(stroke
				(width 0.1524)
				(type default)
			)
			(layer "F.SilkS")
		)
		(fp_line
			(start -4.2291 -1.397)
			(end 3.81 -1.397)
			(stroke
				(width 0.1524)
				(type default)
			)
			(layer "F.SilkS")
		)
		(fp_line
			(start -4.2291 -0.8001)
			(end -3.429 0)
			(stroke
				(width 0.1524)
				(type default)
			)
			(layer "F.SilkS")
		)
		(fp_line
			(start -3.429 0)
			(end -4.2291 0.8001)
			(stroke
				(width 0.1524)
				(type default)
			)
			(layer "F.SilkS")
		)
		(fp_line
			(start 3.81 1.397)
			(end -4.2291 1.397)
			(stroke
				(width 0.1524)
				(type default)
			)
			(layer "F.SilkS")
		)
		(fp_line
			(start -4.22656 3.81)
			(end -4.2291 1.397)
			(stroke
				(width 0.508)
				(type default)
			)
			(layer "F.SilkS")
		)
		(fp_line
			(start -4.2291 3.937)
			(end -4.2291 -1.397)
			(stroke
				(width 0.1524)
				(type default)
			)
			(layer "F.SilkS")
		)
		(fp_poly
			(pts
				(xy -3.90652 -1.8542) (xy 3.90652 -1.8542) (xy 3.90652 1.8542) (xy -3.90652 1.8542)
			)
			(stroke
				(width 0)
				(type default)
			)
			(fill yes)
			(layer "F.SilkS")
		)
		(fp_poly
			(pts
				(xy -4.2164 3.81) (xy 4.2164 3.81) (xy 4.22656 -3.81) (xy -4.2164 -3.81)
			)
			(stroke
				(width 0)
				(type default)
			)
			(fill no)
			(layer "F.CrtYd")
		)
		(fp_poly
			(pts
				(xy -4.22656 -3.81) (xy 4.22656 -3.81) (xy 4.22656 3.81) (xy -4.22656 3.81)
			)
			(stroke
				(width 0)
				(type default)
			)
			(fill no)
			(layer "F.Fab")
		)
		(pad "1" smd rect
			(at -3.57632 2.8194 90)
			(size 0.3556 1.524)
			(layers "F.Cu" "F.Mask" "F.Paste")
			(net "IO_EXP_B_RESET#_FLT")
		)
		(pad "2" smd rect
			(at -2.92608 2.8194 90)
			(size 0.3556 1.524)
			(layers "F.Cu" "F.Mask" "F.Paste")
			(net "TCA9555_B_A1")
		)
		(pad "3" smd rect
			(at -2.27584 2.8194 90)
			(size 0.3556 1.524)
			(layers "F.Cu" "F.Mask" "F.Paste")
			(net "TCA9555_B_A2")
		)
		(pad "4" smd rect
			(at -1.6256 2.8194 90)
			(size 0.3556 1.524)
			(layers "F.Cu" "F.Mask" "F.Paste")
			(net "Net_53")
		)
		(pad "5" smd rect
			(at -0.97536 2.8194 90)
			(size 0.3556 1.524)
			(layers "F.Cu" "F.Mask" "F.Paste")
			(net "Net_52")
		)
		(pad "6" smd rect
			(at -0.32512 2.8194 90)
			(size 0.3556 1.524)
			(layers "F.Cu" "F.Mask" "F.Paste")
			(net "Net_51")
		)
		(pad "7" smd rect
			(at 0.32512 2.8194 90)
			(size 0.3556 1.524)
			(layers "F.Cu" "F.Mask" "F.Paste")
			(net "Net_50")
		)
		(pad "8" smd rect
			(at 0.97536 2.8194 90)
			(size 0.3556 1.524)
			(layers "F.Cu" "F.Mask" "F.Paste")
			(net "Net_49")
		)
		(pad "9" smd rect
			(at 1.6256 2.8194 90)
			(size 0.3556 1.524)
			(layers "F.Cu" "F.Mask" "F.Paste")
			(net "Net_48")
		)
		(pad "10" smd rect
			(at 2.27584 2.8194 90)
			(size 0.3556 1.524)
			(layers "F.Cu" "F.Mask" "F.Paste")
			(net "Net_47")
		)
		(pad "11" smd rect
			(at 2.92608 2.8194 90)
			(size 0.3556 1.524)
			(layers "F.Cu" "F.Mask" "F.Paste")
			(net "Net_46")
		)
		(pad "12" smd rect
			(at 3.57632 2.8194 90)
			(size 0.3556 1.524)
			(layers "F.Cu" "F.Mask" "F.Paste")
			(net "GND")
		)
		(pad "13" smd rect
			(at 3.57632 -2.8194 90)
			(size 0.3556 1.524)
			(layers "F.Cu" "F.Mask" "F.Paste")
			(net "DEBUG_RST_B_BTN_N")
		)
		(pad "14" smd rect
			(at 2.92608 -2.8194 90)
			(size 0.3556 1.524)
			(layers "F.Cu" "F.Mask" "F.Paste")
			(net "Net_45")
		)
		(pad "15" smd rect
			(at 2.27584 -2.8194 90)
			(size 0.3556 1.524)
			(layers "F.Cu" "F.Mask" "F.Paste")
			(net "Net_44")
		)
		(pad "16" smd rect
			(at 1.6256 -2.8194 90)
			(size 0.3556 1.524)
			(layers "F.Cu" "F.Mask" "F.Paste")
			(net "Net_43")
		)
		(pad "17" smd rect
			(at 0.97536 -2.8194 90)
			(size 0.3556 1.524)
			(layers "F.Cu" "F.Mask" "F.Paste")
			(net "Net_42")
		)
		(pad "18" smd rect
			(at 0.32512 -2.8194 90)
			(size 0.3556 1.524)
			(layers "F.Cu" "F.Mask" "F.Paste")
			(net "Net_41")
		)
		(pad "19" smd rect
			(at -0.32512 -2.8194 90)
			(size 0.3556 1.524)
			(layers "F.Cu" "F.Mask" "F.Paste")
			(net "Net_40")
		)
		(pad "20" smd rect
			(at -0.97536 -2.8194 90)
			(size 0.3556 1.524)
			(layers "F.Cu" "F.Mask" "F.Paste")
			(net "DEBUG_HDR_B_UART_SEL")
		)
		(pad "21" smd rect
			(at -1.6256 -2.8194 90)
			(size 0.3556 1.524)
			(layers "F.Cu" "F.Mask" "F.Paste")
			(net "TCA9555_B_A0")
		)
		(pad "22" smd rect
			(at -2.27584 -2.8194 90)
			(size 0.3556 1.524)
			(layers "F.Cu" "F.Mask" "F.Paste")
			(net "I2C_DEBUG_B_SCL_R")
		)
		(pad "23" smd rect
			(at -2.92608 -2.8194 90)
			(size 0.3556 1.524)
			(layers "F.Cu" "F.Mask" "F.Paste")
			(net "I2C_DEBUG_B_SDA_R")
		)
		(pad "24" smd rect
			(at -3.57632 -2.8194 90)
			(size 0.3556 1.524)
			(layers "F.Cu" "F.Mask" "F.Paste")
			(net "P3V3_STBY_B")
		)
	)
	(footprint ""
		(layer "F.Cu")
		(at 52.90566 -70.136512 90)
		(property "Reference" "C17"
			(at 0 0 90)
			(layer "F.SilkS")
			(hide yes)
			(effects
				(font
					(size 1.27 1.27)
				)
			)
		)
		(property "Value" "SC1000P2KV6KX-GP-U"
			(at 0.0508 -3.5052 90)
			(unlocked yes)
			(layer "F.Fab")
			(hide yes)
			(effects
				(font
					(size 1.016 1.016)
					(thickness 0.1524)
				)
			)
		)
		(property "Device Type" "C1206H58"
			(at 0.0508 -5.0292 90)
			(unlocked yes)
			(layer "F.Fab")
			(hide yes)
			(effects
				(font
					(size 1.016 1.016)
					(thickness 0.1524)
				)
			)
		)
		(duplicate_pad_numbers_are_jumpers no)
		(fp_line
			(start 1.016 -2.2352)
			(end -1.016 -2.2352)
			(stroke
				(width 0.1524)
				(type default)
			)
			(layer "F.SilkS")
		)
		(fp_line
			(start 1.016 -2.2352)
			(end 1.016 -0.8382)
			(stroke
				(width 0.1524)
				(type default)
			)
			(layer "F.SilkS")
		)
		(fp_line
			(start -1.016 -2.2352)
			(end -1.016 -0.8382)
			(stroke
				(width 0.1524)
				(type default)
			)
			(layer "F.SilkS")
		)
		(fp_line
			(start 1.016 0.8382)
			(end 1.016 2.2352)
			(stroke
				(width 0.1524)
				(type default)
			)
			(layer "F.SilkS")
		)
		(fp_line
			(start 1.016 2.2352)
			(end -1.016 2.2352)
			(stroke
				(width 0.1524)
				(type default)
			)
			(layer "F.SilkS")
		)
		(fp_line
			(start -1.016 2.2352)
			(end -1.016 0.8128)
			(stroke
				(width 0.1524)
				(type default)
			)
			(layer "F.SilkS")
		)
		(fp_rect
			(start -1.0922 2.3114)
			(end 1.0922 -2.3114)
			(stroke
				(width 0)
				(type default)
			)
			(fill no)
			(layer "F.CrtYd")
		)
		(fp_poly
			(pts
				(xy -1.0922 -2.3114) (xy 1.0922 -2.3114) (xy 1.0922 2.3114) (xy -1.0922 2.3114)
			)
			(stroke
				(width 0)
				(type default)
			)
			(fill no)
			(layer "F.Fab")
		)
		(pad "1" smd rect
			(at 0 -1.397 90)
			(size 1.651 1.27)
			(layers "F.Cu" "F.Mask" "F.Paste")
			(net "USB_CONN_B_GND")
		)
		(pad "2" smd rect
			(at 0 1.397 90)
			(size 1.651 1.27)
			(layers "F.Cu" "F.Mask" "F.Paste")
			(net "GND")
		)
	)
	(footprint ""
		(layer "F.Cu")
		(at 31.496 -13.716 -90)
		(property "Reference" "R17"
			(at 0 0 270)
			(layer "F.SilkS")
			(hide yes)
			(effects
				(font
					(size 1.27 1.27)
				)
			)
		)
		(property "Value" "0R2J-2-GP"
			(at 0.064008 -3.993896 270)
			(unlocked yes)
			(layer "F.Fab")
			(hide yes)
			(effects
				(font
					(size 1.016 1.016)
					(thickness 0.1524)
				)
			)
		)
		(property "Device Type" "R402H16"
			(at 0.064008 -5.517896 270)
			(unlocked yes)
			(layer "F.Fab")
			(hide yes)
			(effects
				(font
					(size 1.016 1.016)
					(thickness 0.1524)
				)
			)
		)
		(duplicate_pad_numbers_are_jumpers no)
		(fp_line
			(start -0.508 -0.9398)
			(end -0.508 0.9398)
			(stroke
				(width 0.1524)
				(type default)
			)
			(layer "F.SilkS")
		)
		(fp_line
			(start 0.508 -0.9398)
			(end -0.508 -0.9398)
			(stroke
				(width 0.1524)
				(type default)
			)
			(layer "F.SilkS")
		)
		(fp_rect
			(start -0.508 0.9398)
			(end 0.508 -0.9398)
			(stroke
				(width 0)
				(type default)
			)
			(fill no)
			(layer "F.CrtYd")
		)
		(fp_rect
			(start -0.508 0.9398)
			(end 0.508 -0.9398)
			(stroke
				(width 0)
				(type default)
			)
			(fill no)
			(layer "F.Fab")
		)
		(pad "1" smd custom
			(at 0 -0.4445 270)
			(size 0.1397 0.1397)
			(layers "F.Cu" "F.Mask" "F.Paste")
			(net "D_FLIP_B_D")
			(options
				(clearance outline)
				(anchor circle)
			)
			(primitives
				(gr_poly
					(pts
						(arc
							(start -0.1778 -0.2794)
							(mid -0.249642 -0.249642)
							(end -0.2794 -0.1778)
						)
						(arc
							(start -0.2794 0.1778)
							(mid -0.249642 0.249642)
							(end -0.1778 0.2794)
						)
						(arc
							(start 0.1778 0.2794)
							(mid 0.249642 0.249642)
							(end 0.2794 0.1778)
						)
						(arc
							(start 0.2794 -0.1778)
							(mid 0.249642 -0.249642)
							(end 0.1778 -0.2794)
						)
					)
					(width 0)
					(fill yes)
				)
			)
		)
		(pad "2" smd custom
			(at 0 0.4445 270)
			(size 0.1397 0.1397)
			(layers "F.Cu" "F.Mask" "F.Paste")
			(net "D_FLIP_B_Q#")
			(options
				(clearance outline)
				(anchor circle)
			)
			(primitives
				(gr_poly
					(pts
						(arc
							(start -0.1778 -0.2794)
							(mid -0.249642 -0.249642)
							(end -0.2794 -0.1778)
						)
						(arc
							(start -0.2794 0.1778)
							(mid -0.249642 0.249642)
							(end -0.1778 0.2794)
						)
						(arc
							(start 0.1778 0.2794)
							(mid 0.249642 0.249642)
							(end 0.2794 0.1778)
						)
						(arc
							(start 0.2794 -0.1778)
							(mid 0.249642 -0.249642)
							(end 0.1778 -0.2794)
						)
					)
					(width 0)
					(fill yes)
				)
			)
		)
	)
)
